FILE_TYPE = MACRO_DRAWING;
SET COLOR_WIRE YELLOW;
SET COLOR_PROP MONO;
SET COLOR_DOT WHITE;
SET COLOR_ARC YELLOW;
SET COLOR_BODY GREEN;
SET COLOR_NOTE MONO;
SET PROP_DISPLAY VALUE;
SET PAGE_NUMBER P142;
FORCEADD TTL1G126_A..1
R 6
(-3500 2250);
FORCEPROP 1 LAST VALUE 74HC1G126
J 0
(-3550 2100);
DISPLAY 0.617021 (-3550 2100);
PAINT SKYBLUE (-3550 2100);
FORCEPROP 1 LASTPIN (-3350 2250) $PN 4
J 0
(-3385 2240);
DISPLAY 0.617021 (-3385 2240);
PAINT WHITE (-3385 2240);
FORCEPROP 1 LASTPIN (-3500 2350) $PN 1
J 0
(-3495 2400);
DISPLAY 0.617021 (-3495 2400);
PAINT WHITE (-3495 2400);
FORCEPROP 1 LAST MATERIAL IC
J 0
(-3600 2500);
DISPLAY 0.617021 (-3600 2500);
PAINT SKYBLUE (-3600 2500);
FORCEPROP 1 LAST LOCATION U8E4
J 0
(-3625 2429);
DISPLAY 0.617021 (-3625 2429);
PAINT AQUA (-3625 2429);
FORCEPROP 1 LASTPIN (-3650 2250) $PN 2
J 2
(-3625 2240);
DISPLAY 0.617021 (-3625 2240);
PAINT WHITE (-3625 2240);
FORCEPROP 1 LAST PART_NUMBER A79322-001
J 0
(-3400 2340);
DISPLAY 0.617021 (-3400 2340);
PAINT BLUE (-3400 2340);
FORCEPROP 1 LAST POWER_GROUP VCC=P3V3_STBY;GND=GND;
J 0
(-3600 2015);
DISPLAY 0.617021 (-3600 2015);
PAINT ORANGE (-3600 2015);
FORCEPROP 2 LAST CDS_LIB mstr_ttl
J 0
(-3500 2250);
PAINT ORANGE (-3500 2250);
DISPLAY INVISIBLE (-3500 2250);
FORCEPROP 2 LAST SEC_TYPE SOT
J 0
(-3400 2450);
DISPLAY 1.021277 (-3400 2450);
PAINT ORANGE (-3400 2450);
DISPLAY INVISIBLE (-3400 2450);
FORCEPROP 2 LAST BOM_COST SB
J 0
(-3400 2425);
DISPLAY 1.021277 (-3400 2425);
PAINT ORANGE (-3400 2425);
DISPLAY INVISIBLE (-3400 2425);
FORCEPROP 2 LAST SEC 1
J 0
(-3400 2450);
DISPLAY 0.680851 (-3400 2450);
PAINT MONO (-3400 2450);
DISPLAY INVISIBLE (-3400 2450);
FORCEPROP 2 LAST ROOM PCIE_WAKE_BUFFER
J 0
(-3400 2375);
DISPLAY 1.021277 (-3400 2375);
PAINT ORANGE (-3400 2375);
DISPLAY INVISIBLE (-3400 2375);
FORCEPROP 1 LAST PATH I1
J 2
(-3605 2150);
DISPLAY 0.978723 (-3605 2150);
PAINT GREEN (-3605 2150);
DISPLAY INVISIBLE (-3605 2150);
FORCEPROP 2 LAST CDS_LOCATION U8E4
J 0
(-3550 2004);
DISPLAY 0.617021 (-3550 2004);
PAINT AQUA (-3550 2004);
DISPLAY INVISIBLE (-3550 2004);
FORCEPROP 1 LAST PACK_TYPE SOT
J 0
(-3550 2000);
DISPLAY 0.978723 (-3550 2000);
PAINT SKYBLUE (-3550 2000);
DISPLAY INVISIBLE (-3550 2000);
FORCEADD OFFPAGE..1
(-5450 2650);
FORCEPROP 2 LAST $XR0 185 
J 0
(-5732 2650);
DISPLAY 0.638298 (-5732 2650);
PAINT MONO (-5732 2650);
FORCEPROP 2 LAST CDS_LIB mstr_standard
J 0
(-5450 2650);
PAINT ORANGE (-5450 2650);
DISPLAY INVISIBLE (-5450 2650);
FORCEPROP 2 LAST PATH I11
J 0
(-5400 2725);
DISPLAY 1.021277 (-5400 2725);
PAINT ORANGE (-5400 2725);
DISPLAY INVISIBLE (-5400 2725);
FORCEPROP 1 LAST OFFPAGE TRUE
J 0
(-5125 2525);
DISPLAY 0.872340 (-5125 2525);
PAINT GREEN (-5125 2525);
DISPLAY INVISIBLE (-5125 2525);
FORCEPROP 1 LAST COMMENT_BODY TRUE
J 0
(-5325 2550);
DISPLAY 0.872340 (-5325 2550);
PAINT GREEN (-5325 2550);
DISPLAY INVISIBLE (-5325 2550);
FORCEADD OFFPAGE..1
(-5450 2450);
FORCEPROP 2 LAST $XR0 108 
J 0
(-5732 2450);
DISPLAY 0.638298 (-5732 2450);
PAINT MONO (-5732 2450);
FORCEPROP 2 LAST CDS_LIB mstr_standard
J 0
(-5450 2450);
PAINT ORANGE (-5450 2450);
DISPLAY INVISIBLE (-5450 2450);
FORCEPROP 2 LAST PATH I12
J 0
(-5400 2525);
DISPLAY 1.021277 (-5400 2525);
PAINT ORANGE (-5400 2525);
DISPLAY INVISIBLE (-5400 2525);
FORCEPROP 1 LAST OFFPAGE TRUE
J 0
(-5125 2325);
DISPLAY 0.872340 (-5125 2325);
PAINT GREEN (-5125 2325);
DISPLAY INVISIBLE (-5125 2325);
FORCEPROP 1 LAST COMMENT_BODY TRUE
J 0
(-5325 2350);
DISPLAY 0.872340 (-5325 2350);
PAINT GREEN (-5325 2350);
DISPLAY INVISIBLE (-5325 2350);
FORCEADD OFFPAGE..1
(-5450 2250);
FORCEPROP 2 LAST $XR0 186 
J 0
(-5732 2250);
DISPLAY 0.638298 (-5732 2250);
PAINT MONO (-5732 2250);
FORCEPROP 1 LAST COMMENT_BODY TRUE
J 0
(-5325 2150);
DISPLAY 0.872340 (-5325 2150);
PAINT GREEN (-5325 2150);
DISPLAY INVISIBLE (-5325 2150);
FORCEPROP 1 LAST OFFPAGE TRUE
J 0
(-5125 2125);
DISPLAY 0.872340 (-5125 2125);
PAINT GREEN (-5125 2125);
DISPLAY INVISIBLE (-5125 2125);
FORCEPROP 2 LAST PATH I13
J 0
(-5400 2325);
DISPLAY 1.021277 (-5400 2325);
PAINT ORANGE (-5400 2325);
DISPLAY INVISIBLE (-5400 2325);
FORCEPROP 2 LAST CDS_LIB mstr_standard
J 0
(-5450 2250);
PAINT ORANGE (-5450 2250);
DISPLAY INVISIBLE (-5450 2250);
FORCEADD OFFPAGE..1
(-5450 2850);
FORCEPROP 2 LAST $XR0 139 
J 0
(-5732 2850);
DISPLAY 0.638298 (-5732 2850);
PAINT MONO (-5732 2850);
FORCEPROP 2 LAST CDS_LIB mstr_standard
J 0
(-5450 2850);
PAINT ORANGE (-5450 2850);
DISPLAY INVISIBLE (-5450 2850);
FORCEPROP 2 LAST PATH I17
J 0
(-5400 2925);
DISPLAY 1.021277 (-5400 2925);
PAINT ORANGE (-5400 2925);
DISPLAY INVISIBLE (-5400 2925);
FORCEPROP 1 LAST OFFPAGE TRUE
J 0
(-5125 2725);
DISPLAY 0.872340 (-5125 2725);
PAINT GREEN (-5125 2725);
DISPLAY INVISIBLE (-5125 2725);
FORCEPROP 1 LAST COMMENT_BODY TRUE
J 0
(-5325 2750);
DISPLAY 0.872340 (-5325 2750);
PAINT GREEN (-5325 2750);
DISPLAY INVISIBLE (-5325 2750);
FORCEADD RES..1
(-4550 3100);
FORCEPROP 1 LAST PACK_TYPE 0402
J 0
(-4450 2975);
DISPLAY 0.617021 (-4450 2975);
PAINT SKYBLUE (-4450 2975);
FORCEPROP 1 LAST MATERIAL EMPTY
J 0
(-4300 2975);
DISPLAY 0.617021 (-4300 2975);
PAINT RED (-4300 2975);
FORCEPROP 1 LASTPIN (-4650 3100) $PN 1
J 0
(-4638 3112);
DISPLAY 0.617021 (-4638 3112);
PAINT ORANGE (-4638 3112);
FORCEPROP 1 LASTPIN (-4450 3100) $PN 2
J 0
(-4488 3112);
DISPLAY 0.617021 (-4488 3112);
PAINT ORANGE (-4488 3112);
FORCEPROP 1 LAST LOCATION R8E29
J 0
(-4750 2975);
DISPLAY 0.617021 (-4750 2975);
PAINT AQUA (-4750 2975);
FORCEPROP 1 LAST VALUE 0.0
J 0
(-4750 2925);
DISPLAY 0.617021 (-4750 2925);
PAINT SKYBLUE (-4750 2925);
FORCEPROP 1 LAST TOLERANCE 5%
J 0
(-4600 2975);
DISPLAY 0.617021 (-4600 2975);
PAINT SKYBLUE (-4600 2975);
FORCEPROP 1 LAST PART_NUMBER G21497-005
J 0
(-4450 2925);
DISPLAY 0.617021 (-4450 2925);
PAINT BLUE (-4450 2925);
FORCEPROP 1 LAST WATTAGE 1/16W
J 0
(-4600 2925);
DISPLAY 0.617021 (-4600 2925);
PAINT SKYBLUE (-4600 2925);
FORCEPROP 2 LAST SEC 1
J 0
(-4600 3300);
PAINT MONO (-4600 3300);
DISPLAY INVISIBLE (-4600 3300);
FORCEPROP 2 LAST SEC_TYPE 0402
J 0
(-4600 3300);
DISPLAY 1.021277 (-4600 3300);
PAINT ORANGE (-4600 3300);
DISPLAY INVISIBLE (-4600 3300);
FORCEPROP 2 LAST ROOM PCIE_WAKE_BUFFER
J 0
(-4600 3200);
DISPLAY 1.021277 (-4600 3200);
PAINT ORANGE (-4600 3200);
DISPLAY INVISIBLE (-4600 3200);
FORCEPROP 1 LAST PATH I18
J 0
(-4600 3250);
DISPLAY 0.978723 (-4600 3250);
PAINT WHITE (-4600 3250);
DISPLAY INVISIBLE (-4600 3250);
FORCEPROP 2 LAST BOM_COST SB
J 0
(-4600 3250);
DISPLAY 1.021277 (-4600 3250);
PAINT ORANGE (-4600 3250);
DISPLAY INVISIBLE (-4600 3250);
FORCEPROP 2 LAST CDS_LOCATION R8E29
J 0
(-4600 3150);
DISPLAY 0.617021 (-4600 3150);
PAINT AQUA (-4600 3150);
DISPLAY INVISIBLE (-4600 3150);
FORCEPROP 2 LAST CDS_LIB mstr_discrete
J 0
(-4550 3100);
PAINT ORANGE (-4550 3100);
DISPLAY INVISIBLE (-4550 3100);
FORCEADD OFFPAGE..1
(-5450 3100);
FORCEPROP 2 LAST $XR0 146 
J 0
(-5732 3100);
DISPLAY 0.638298 (-5732 3100);
PAINT MONO (-5732 3100);
FORCEPROP 1 LAST COMMENT_BODY TRUE
J 0
(-5325 3000);
DISPLAY 0.872340 (-5325 3000);
PAINT GREEN (-5325 3000);
DISPLAY INVISIBLE (-5325 3000);
FORCEPROP 1 LAST OFFPAGE TRUE
J 0
(-5125 2975);
DISPLAY 0.872340 (-5125 2975);
PAINT GREEN (-5125 2975);
DISPLAY INVISIBLE (-5125 2975);
FORCEPROP 2 LAST PATH I19
J 0
(-5400 3175);
DISPLAY 1.021277 (-5400 3175);
PAINT ORANGE (-5400 3175);
DISPLAY INVISIBLE (-5400 3175);
FORCEPROP 2 LAST CDS_LIB mstr_standard
J 0
(-5450 3100);
PAINT ORANGE (-5450 3100);
DISPLAY INVISIBLE (-5450 3100);
FORCEADD RES..1
(-2600 2250);
FORCEPROP 1 LAST WATTAGE 1/16W
J 2
(-2625 2100);
DISPLAY 0.617021 (-2625 2100);
PAINT SKYBLUE (-2625 2100);
FORCEPROP 1 LAST PACK_TYPE 0402
J 0
(-2450 2100);
DISPLAY 0.617021 (-2450 2100);
PAINT SKYBLUE (-2450 2100);
FORCEPROP 1 LASTPIN (-2500 2250) $PN 2
J 0
(-2538 2262);
DISPLAY 0.617021 (-2538 2262);
PAINT ORANGE (-2538 2262);
FORCEPROP 1 LAST LOCATION R8E17
J 0
(-2650 2300);
DISPLAY 0.617021 (-2650 2300);
PAINT AQUA (-2650 2300);
FORCEPROP 1 LAST TOLERANCE 1%
J 0
(-2600 2150);
DISPLAY 0.617021 (-2600 2150);
PAINT SKYBLUE (-2600 2150);
FORCEPROP 1 LAST MATERIAL CHIP
J 0
(-2600 2100);
DISPLAY 0.617021 (-2600 2100);
PAINT SKYBLUE (-2600 2100);
FORCEPROP 1 LAST VALUE 33.2
J 2
(-2625 2150);
DISPLAY 0.617021 (-2625 2150);
PAINT SKYBLUE (-2625 2150);
FORCEPROP 1 LASTPIN (-2700 2250) $PN 1
J 0
(-2688 2262);
DISPLAY 0.617021 (-2688 2262);
PAINT ORANGE (-2688 2262);
FORCEPROP 1 LAST PART_NUMBER G21796-074
J 0
(-2650 2350);
DISPLAY 0.617021 (-2650 2350);
PAINT BLUE (-2650 2350);
FORCEPROP 2 LAST ROOM PCIE_WAKE_BUFFER
J 0
(-2650 2400);
DISPLAY 1.021277 (-2650 2400);
PAINT ORANGE (-2650 2400);
DISPLAY INVISIBLE (-2650 2400);
FORCEPROP 1 LAST PATH I2
J 0
(-2650 2400);
DISPLAY 0.978723 (-2650 2400);
PAINT WHITE (-2650 2400);
DISPLAY INVISIBLE (-2650 2400);
FORCEPROP 2 LAST CDS_LOCATION R8E17
J 0
(-2650 2300);
DISPLAY 0.617021 (-2650 2300);
PAINT AQUA (-2650 2300);
DISPLAY INVISIBLE (-2650 2300);
FORCEPROP 2 LAST SEC 1
J 0
(-2650 2450);
PAINT MONO (-2650 2450);
DISPLAY INVISIBLE (-2650 2450);
FORCEPROP 2 LAST BOM_COST SB
J 0
(-2650 2450);
DISPLAY 1.021277 (-2650 2450);
PAINT ORANGE (-2650 2450);
DISPLAY INVISIBLE (-2650 2450);
FORCEPROP 2 LAST SEC_TYPE 0402
J 0
(-2650 2450);
DISPLAY 1.021277 (-2650 2450);
PAINT ORANGE (-2650 2450);
DISPLAY INVISIBLE (-2650 2450);
FORCEPROP 2 LAST CDS_LIB mstr_discrete
J 0
(-2600 2250);
PAINT ORANGE (-2600 2250);
DISPLAY INVISIBLE (-2600 2250);
FORCEADD CAP_A..1
(-3500 1550);
FORCEPROP 1 LAST VALUE 0.1UF
J 0
(-3450 1600);
DISPLAY 0.617021 (-3450 1600);
PAINT SKYBLUE (-3450 1600);
FORCEPROP 1 LAST VOLTAGE 16V
J 0
(-3450 1550);
DISPLAY 0.617021 (-3450 1550);
PAINT SKYBLUE (-3450 1550);
FORCEPROP 1 LAST LOCATION C8E5
J 0
(-3450 1650);
DISPLAY 0.617021 (-3450 1650);
PAINT AQUA (-3450 1650);
FORCEPROP 1 LASTPIN (-3500 1650) $PN 1
J 0
(-3490 1630);
DISPLAY 0.617021 (-3490 1630);
PAINT ORANGE (-3490 1630);
FORCEPROP 1 LAST PACK_TYPE 0402V
J 0
(-3450 1350);
DISPLAY 0.617021 (-3450 1350);
PAINT SKYBLUE (-3450 1350);
FORCEPROP 1 LAST PART_NUMBER A36096-030
J 0
(-3450 1400);
DISPLAY 0.617021 (-3450 1400);
PAINT BLUE (-3450 1400);
FORCEPROP 1 LASTPIN (-3500 1450) $PN 2
J 0
(-3490 1430);
DISPLAY 0.617021 (-3490 1430);
PAINT ORANGE (-3490 1430);
FORCEPROP 1 LAST MATERIAL X7R
J 0
(-3450 1450);
DISPLAY 0.617021 (-3450 1450);
PAINT SKYBLUE (-3450 1450);
FORCEPROP 1 LAST TOLERANCE 10%
J 0
(-3450 1500);
DISPLAY 0.617021 (-3450 1500);
PAINT SKYBLUE (-3450 1500);
FORCEPROP 2 LAST BOM_COST SB
J 0
(-3450 1750);
DISPLAY 1.021277 (-3450 1750);
PAINT ORANGE (-3450 1750);
DISPLAY INVISIBLE (-3450 1750);
FORCEPROP 2 LAST SEC_TYPE 0402V
J 0
(-3450 1750);
DISPLAY 1.021277 (-3450 1750);
PAINT ORANGE (-3450 1750);
DISPLAY INVISIBLE (-3450 1750);
FORCEPROP 2 LAST SEC 1
J 0
(-3450 1750);
PAINT MONO (-3450 1750);
DISPLAY INVISIBLE (-3450 1750);
FORCEPROP 1 LAST PATH I20
J 0
(-3450 1700);
DISPLAY 0.978723 (-3450 1700);
PAINT WHITE (-3450 1700);
DISPLAY INVISIBLE (-3450 1700);
FORCEPROP 2 LAST ROOM PCIE_WAKE_BUFFER
J 0
(-3450 1700);
DISPLAY 1.021277 (-3450 1700);
PAINT ORANGE (-3450 1700);
DISPLAY INVISIBLE (-3450 1700);
FORCEPROP 2 LAST CDS_LOCATION C8E5
J 0
(-3450 1650);
DISPLAY 0.617021 (-3450 1650);
PAINT AQUA (-3450 1650);
DISPLAY INVISIBLE (-3450 1650);
FORCEPROP 2 LAST CDS_SEC 1
J 0
(-3450 1700);
PAINT ORANGE (-3450 1700);
DISPLAY INVISIBLE (-3450 1700);
FORCEPROP 2 LAST CDS_LIB dev_discrete
J 0
(-3500 1550);
PAINT ORANGE (-3500 1550);
DISPLAY INVISIBLE (-3500 1550);
FORCEADD P3V3_STBY..1
(-3500 1775);
FORCEPROP 3 LASTPIN (-3500 1725) SIG_NAME P3V3_STBY\g
J 0
(-3490 1735);
DISPLAY 0.659574 (-3490 1735);
PAINT MONO (-3490 1735);
DISPLAY INVISIBLE (-3490 1735);
FORCEPROP 1 LAST HDL_POWER P3V3_STBY
J 0
(-3800 1650);
DISPLAY 0.872340 (-3800 1650);
PAINT ORANGE (-3800 1650);
DISPLAY INVISIBLE (-3800 1650);
FORCEPROP 1 LAST BODY_TYPE PLUMBING
J 0
(-3545 1732);
DISPLAY 0.340426 (-3545 1732);
PAINT GREEN (-3545 1732);
DISPLAY INVISIBLE (-3545 1732);
FORCEPROP 1 LAST SIZE 1B
J 0
(-3455 1797);
DISPLAY 0.340426 (-3455 1797);
PAINT GREEN (-3455 1797);
DISPLAY INVISIBLE (-3455 1797);
FORCEPROP 2 LAST CDS_LIB mstr_symbols
J 0
(-3500 1775);
PAINT ORANGE (-3500 1775);
DISPLAY INVISIBLE (-3500 1775);
FORCEPROP 1 LAST PATH I21
J 0
(-3455 1777);
DISPLAY 0.340426 (-3455 1777);
PAINT GREEN (-3455 1777);
DISPLAY INVISIBLE (-3455 1777);
FORCEPROP 1 LAST VOLTAGE 3.3V
J 0
(-3545 1732);
DISPLAY 0.340426 (-3545 1732);
PAINT SKYBLUE (-3545 1732);
DISPLAY INVISIBLE (-3545 1732);
FORCEADD GND..1
(-3500 1250);
FORCEPROP 3 LASTPIN (-3500 1300) SIG_NAME GND\g
J 0
(-3490 1310);
DISPLAY 0.659574 (-3490 1310);
PAINT MONO (-3490 1310);
DISPLAY INVISIBLE (-3490 1310);
FORCEPROP 1 LAST HDL_POWER GND
J 0
(-3500 1400);
DISPLAY 0.872340 (-3500 1400);
PAINT GREEN (-3500 1400);
DISPLAY INVISIBLE (-3500 1400);
FORCEPROP 1 LAST BODY_TYPE PLUMBING
J 0
(-3545 1207);
DISPLAY 0.340426 (-3545 1207);
PAINT GREEN (-3545 1207);
DISPLAY INVISIBLE (-3545 1207);
FORCEPROP 1 LAST PATH I22
J 0
(-3425 1250);
DISPLAY 0.872340 (-3425 1250);
PAINT AQUA (-3425 1250);
DISPLAY INVISIBLE (-3425 1250);
FORCEPROP 2 LAST CDS_LIB mstr_symbols
J 0
(-3500 1250);
PAINT ORANGE (-3500 1250);
DISPLAY INVISIBLE (-3500 1250);
FORCEPROP 1 LAST SIZE 1B
J 0
(-3425 1200);
DISPLAY 0.872340 (-3425 1200);
PAINT AQUA (-3425 1200);
DISPLAY INVISIBLE (-3425 1200);
FORCEPROP 1 LAST VOLTAGE 0.0V
J 0
(-3545 1207);
DISPLAY 0.340426 (-3545 1207);
PAINT SKYBLUE (-3545 1207);
DISPLAY INVISIBLE (-3545 1207);
FORCEADD P3V3_STBY..1
(-3800 3900);
FORCEPROP 3 LASTPIN (-3800 3850) SIG_NAME P3V3_STBY\g
J 0
(-3790 3860);
DISPLAY 0.659574 (-3790 3860);
PAINT MONO (-3790 3860);
DISPLAY INVISIBLE (-3790 3860);
FORCEPROP 1 LAST VOLTAGE 3.3V
J 0
(-3845 3857);
DISPLAY 0.340426 (-3845 3857);
PAINT SKYBLUE (-3845 3857);
DISPLAY INVISIBLE (-3845 3857);
FORCEPROP 2 LAST CDS_LIB mstr_symbols
J 0
(-3800 3900);
PAINT ORANGE (-3800 3900);
DISPLAY INVISIBLE (-3800 3900);
FORCEPROP 1 LAST PATH I24
J 0
(-3755 3902);
DISPLAY 0.340426 (-3755 3902);
PAINT GREEN (-3755 3902);
DISPLAY INVISIBLE (-3755 3902);
FORCEPROP 1 LAST SIZE 1B
J 0
(-3755 3922);
DISPLAY 0.340426 (-3755 3922);
PAINT GREEN (-3755 3922);
DISPLAY INVISIBLE (-3755 3922);
FORCEPROP 1 LAST BODY_TYPE PLUMBING
J 0
(-3845 3857);
DISPLAY 0.340426 (-3845 3857);
PAINT GREEN (-3845 3857);
DISPLAY INVISIBLE (-3845 3857);
FORCEPROP 1 LAST HDL_POWER P3V3_STBY
J 0
(-4100 3775);
DISPLAY 0.872340 (-4100 3775);
PAINT ORANGE (-4100 3775);
DISPLAY INVISIBLE (-4100 3775);
FORCEADD RES..1
(-2850 2700);
FORCEPROP 1 LAST VALUE 4.75K
J 2
(-2875 2600);
DISPLAY 0.617021 (-2875 2600);
PAINT SKYBLUE (-2875 2600);
FORCEPROP 1 LAST WATTAGE 1/16W
J 2
(-2875 2550);
DISPLAY 0.617021 (-2875 2550);
PAINT SKYBLUE (-2875 2550);
FORCEPROP 1 LAST MATERIAL CHIP
J 0
(-2850 2550);
DISPLAY 0.617021 (-2850 2550);
PAINT SKYBLUE (-2850 2550);
FORCEPROP 1 LAST PACK_TYPE 0402
J 0
(-2725 2550);
DISPLAY 0.617021 (-2725 2550);
PAINT SKYBLUE (-2725 2550);
FORCEPROP 1 LAST LOCATION R8E23
J 0
(-2900 2750);
DISPLAY 0.617021 (-2900 2750);
PAINT AQUA (-2900 2750);
FORCEPROP 1 LASTPIN (-2950 2700) $PN 1
J 0
(-2938 2712);
DISPLAY 0.617021 (-2938 2712);
PAINT ORANGE (-2938 2712);
FORCEPROP 1 LAST PART_NUMBER G21796-072
J 0
(-2900 2800);
DISPLAY 0.617021 (-2900 2800);
PAINT BLUE (-2900 2800);
FORCEPROP 1 LAST TOLERANCE 1%
J 0
(-2850 2600);
DISPLAY 0.617021 (-2850 2600);
PAINT SKYBLUE (-2850 2600);
FORCEPROP 1 LASTPIN (-2750 2700) $PN 2
J 0
(-2788 2712);
DISPLAY 0.617021 (-2788 2712);
PAINT ORANGE (-2788 2712);
FORCEPROP 2 LAST BOM_COST SB
J 0
(-2900 2900);
DISPLAY 1.021277 (-2900 2900);
PAINT ORANGE (-2900 2900);
DISPLAY INVISIBLE (-2900 2900);
FORCEPROP 2 LAST SEC 1
J 0
(-2900 2900);
PAINT MONO (-2900 2900);
DISPLAY INVISIBLE (-2900 2900);
FORCEPROP 1 LAST PATH I3
J 0
(-2900 2850);
DISPLAY 0.978723 (-2900 2850);
PAINT WHITE (-2900 2850);
DISPLAY INVISIBLE (-2900 2850);
FORCEPROP 2 LAST ROOM PCIE_WAKE_BUFFER
J 0
(-2900 2850);
DISPLAY 1.021277 (-2900 2850);
PAINT ORANGE (-2900 2850);
DISPLAY INVISIBLE (-2900 2850);
FORCEPROP 2 LAST SEC_TYPE 0402
J 0
(-2900 2900);
DISPLAY 1.021277 (-2900 2900);
PAINT ORANGE (-2900 2900);
DISPLAY INVISIBLE (-2900 2900);
FORCEPROP 2 LAST CDS_LOCATION R8E23
J 0
(-2900 2750);
DISPLAY 0.617021 (-2900 2750);
PAINT AQUA (-2900 2750);
DISPLAY INVISIBLE (-2900 2750);
FORCEPROP 2 LAST CDS_LIB mstr_discrete
J 0
(-2850 2700);
PAINT ORANGE (-2850 2700);
DISPLAY INVISIBLE (-2850 2700);
FORCEADD RES..1
(-4550 2250);
FORCEPROP 1 LASTPIN (-4650 2250) $PN 1
J 0
(-4638 2262);
DISPLAY 0.617021 (-4638 2262);
PAINT ORANGE (-4638 2262);
FORCEPROP 1 LASTPIN (-4450 2250) $PN 2
J 0
(-4488 2262);
DISPLAY 0.617021 (-4488 2262);
PAINT ORANGE (-4488 2262);
FORCEPROP 1 LAST LOCATION R8E26
J 0
(-4700 2175);
DISPLAY 0.617021 (-4700 2175);
PAINT AQUA (-4700 2175);
FORCEPROP 1 LAST VALUE 0.0
J 0
(-4700 2125);
DISPLAY 0.617021 (-4700 2125);
PAINT SKYBLUE (-4700 2125);
FORCEPROP 1 LAST TOLERANCE 5%
J 0
(-4550 2175);
DISPLAY 0.617021 (-4550 2175);
PAINT SKYBLUE (-4550 2175);
FORCEPROP 1 LAST WATTAGE 1/16W
J 0
(-4550 2125);
DISPLAY 0.617021 (-4550 2125);
PAINT SKYBLUE (-4550 2125);
FORCEPROP 1 LAST PACK_TYPE 0402
J 0
(-4400 2175);
DISPLAY 0.617021 (-4400 2175);
PAINT SKYBLUE (-4400 2175);
FORCEPROP 1 LAST PART_NUMBER G21497-005
J 0
(-4400 2125);
DISPLAY 0.617021 (-4400 2125);
PAINT BLUE (-4400 2125);
FORCEPROP 1 LAST MATERIAL CHIP
J 0
(-4250 2175);
DISPLAY 0.617021 (-4250 2175);
PAINT SKYBLUE (-4250 2175);
FORCEPROP 2 LAST CDS_LIB mstr_discrete
J 0
(-4550 2250);
PAINT ORANGE (-4550 2250);
DISPLAY INVISIBLE (-4550 2250);
FORCEPROP 0 LAST ROOM PCIE_WAKE_BUFFER
J 0
(-4600 2400);
DISPLAY 1.021277 (-4600 2400);
PAINT ORANGE (-4600 2400);
DISPLAY INVISIBLE (-4600 2400);
FORCEPROP 1 LAST PATH I30
J 0
(-4600 2400);
DISPLAY 0.978723 (-4600 2400);
PAINT WHITE (-4600 2400);
DISPLAY INVISIBLE (-4600 2400);
FORCEPROP 2 LAST CDS_LOCATION R8E26
J 0
(-4600 2300);
DISPLAY 0.617021 (-4600 2300);
PAINT AQUA (-4600 2300);
DISPLAY INVISIBLE (-4600 2300);
FORCEPROP 2 LAST SEC 1
J 0
(-4600 2450);
DISPLAY 0.680851 (-4600 2450);
PAINT MONO (-4600 2450);
DISPLAY INVISIBLE (-4600 2450);
FORCEPROP 2 LAST SEC_TYPE 0402
J 0
(-4600 2450);
DISPLAY 1.021277 (-4600 2450);
PAINT ORANGE (-4600 2450);
DISPLAY INVISIBLE (-4600 2450);
FORCEADD RES..1
(-4550 2450);
FORCEPROP 1 LAST LOCATION R8E28
J 0
(-4750 2375);
DISPLAY 0.617021 (-4750 2375);
PAINT AQUA (-4750 2375);
FORCEPROP 1 LAST VALUE 0.0
J 0
(-4750 2325);
DISPLAY 0.617021 (-4750 2325);
PAINT SKYBLUE (-4750 2325);
FORCEPROP 1 LAST PACK_TYPE 0402
J 0
(-4450 2375);
DISPLAY 0.617021 (-4450 2375);
PAINT SKYBLUE (-4450 2375);
FORCEPROP 1 LAST PART_NUMBER G21497-005
J 0
(-4450 2325);
DISPLAY 0.617021 (-4450 2325);
PAINT BLUE (-4450 2325);
FORCEPROP 1 LAST MATERIAL CHIP
J 0
(-4300 2375);
DISPLAY 0.617021 (-4300 2375);
PAINT SKYBLUE (-4300 2375);
FORCEPROP 1 LASTPIN (-4450 2450) $PN 2
J 0
(-4488 2462);
DISPLAY 0.617021 (-4488 2462);
PAINT ORANGE (-4488 2462);
FORCEPROP 1 LASTPIN (-4650 2450) $PN 1
J 0
(-4638 2462);
DISPLAY 0.617021 (-4638 2462);
PAINT ORANGE (-4638 2462);
FORCEPROP 1 LAST WATTAGE 1/16W
J 0
(-4600 2325);
DISPLAY 0.617021 (-4600 2325);
PAINT SKYBLUE (-4600 2325);
FORCEPROP 1 LAST TOLERANCE 5%
J 0
(-4600 2375);
DISPLAY 0.617021 (-4600 2375);
PAINT SKYBLUE (-4600 2375);
FORCEPROP 2 LAST CDS_LIB mstr_discrete
J 0
(-4550 2450);
PAINT ORANGE (-4550 2450);
DISPLAY INVISIBLE (-4550 2450);
FORCEPROP 0 LAST ROOM PCIE_WAKE_BUFFER
J 0
(-4600 2600);
DISPLAY 1.021277 (-4600 2600);
PAINT ORANGE (-4600 2600);
DISPLAY INVISIBLE (-4600 2600);
FORCEPROP 1 LAST PATH I31
J 0
(-4600 2600);
DISPLAY 0.978723 (-4600 2600);
PAINT WHITE (-4600 2600);
DISPLAY INVISIBLE (-4600 2600);
FORCEPROP 2 LAST SEC 1
J 0
(-4600 2650);
DISPLAY 0.680851 (-4600 2650);
PAINT MONO (-4600 2650);
DISPLAY INVISIBLE (-4600 2650);
FORCEPROP 2 LAST SEC_TYPE 0402
J 0
(-4600 2650);
DISPLAY 1.021277 (-4600 2650);
PAINT ORANGE (-4600 2650);
DISPLAY INVISIBLE (-4600 2650);
FORCEPROP 2 LAST CDS_LOCATION R8E28
J 0
(-4600 2500);
DISPLAY 0.617021 (-4600 2500);
PAINT AQUA (-4600 2500);
DISPLAY INVISIBLE (-4600 2500);
FORCEADD RES..1
(-4550 2650);
FORCEPROP 1 LASTPIN (-4650 2650) $PN 1
J 0
(-4638 2662);
DISPLAY 0.617021 (-4638 2662);
PAINT ORANGE (-4638 2662);
FORCEPROP 1 LAST TOLERANCE 5%
J 0
(-4600 2575);
DISPLAY 0.617021 (-4600 2575);
PAINT SKYBLUE (-4600 2575);
FORCEPROP 1 LAST MATERIAL CHIP
J 0
(-4300 2575);
DISPLAY 0.617021 (-4300 2575);
PAINT SKYBLUE (-4300 2575);
FORCEPROP 1 LAST PACK_TYPE 0402
J 0
(-4450 2575);
DISPLAY 0.617021 (-4450 2575);
PAINT SKYBLUE (-4450 2575);
FORCEPROP 1 LAST PART_NUMBER G21497-005
J 0
(-4450 2525);
DISPLAY 0.617021 (-4450 2525);
PAINT BLUE (-4450 2525);
FORCEPROP 1 LAST LOCATION R8E27
J 0
(-4750 2575);
DISPLAY 0.617021 (-4750 2575);
PAINT AQUA (-4750 2575);
FORCEPROP 1 LAST VALUE 0.0
J 0
(-4750 2525);
DISPLAY 0.617021 (-4750 2525);
PAINT SKYBLUE (-4750 2525);
FORCEPROP 1 LAST WATTAGE 1/16W
J 0
(-4600 2525);
DISPLAY 0.617021 (-4600 2525);
PAINT SKYBLUE (-4600 2525);
FORCEPROP 1 LASTPIN (-4450 2650) $PN 2
J 0
(-4488 2662);
DISPLAY 0.617021 (-4488 2662);
PAINT ORANGE (-4488 2662);
FORCEPROP 2 LAST CDS_LIB mstr_discrete
J 0
(-4550 2650);
PAINT ORANGE (-4550 2650);
DISPLAY INVISIBLE (-4550 2650);
FORCEPROP 0 LAST ROOM PCIE_WAKE_BUFFER
J 0
(-4600 2800);
DISPLAY 1.021277 (-4600 2800);
PAINT ORANGE (-4600 2800);
DISPLAY INVISIBLE (-4600 2800);
FORCEPROP 1 LAST PATH I32
J 0
(-4600 2800);
DISPLAY 0.978723 (-4600 2800);
PAINT WHITE (-4600 2800);
DISPLAY INVISIBLE (-4600 2800);
FORCEPROP 2 LAST CDS_LOCATION R8E27
J 0
(-4600 2700);
DISPLAY 0.617021 (-4600 2700);
PAINT AQUA (-4600 2700);
DISPLAY INVISIBLE (-4600 2700);
FORCEPROP 2 LAST SEC 1
J 0
(-4600 2850);
DISPLAY 0.680851 (-4600 2850);
PAINT MONO (-4600 2850);
DISPLAY INVISIBLE (-4600 2850);
FORCEPROP 2 LAST SEC_TYPE 0402
J 0
(-4600 2850);
DISPLAY 1.021277 (-4600 2850);
PAINT ORANGE (-4600 2850);
DISPLAY INVISIBLE (-4600 2850);
FORCEADD RES..1
(-4550 2850);
FORCEPROP 1 LASTPIN (-4650 2850) $PN 1
J 0
(-4638 2862);
DISPLAY 0.617021 (-4638 2862);
PAINT ORANGE (-4638 2862);
FORCEPROP 1 LAST WATTAGE 1/16W
J 0
(-4600 2725);
DISPLAY 0.617021 (-4600 2725);
PAINT SKYBLUE (-4600 2725);
FORCEPROP 1 LAST TOLERANCE 5%
J 0
(-4600 2775);
DISPLAY 0.617021 (-4600 2775);
PAINT SKYBLUE (-4600 2775);
FORCEPROP 1 LAST LOCATION R8E21
J 0
(-4750 2775);
DISPLAY 0.617021 (-4750 2775);
PAINT AQUA (-4750 2775);
FORCEPROP 1 LASTPIN (-4450 2850) $PN 2
J 0
(-4488 2862);
DISPLAY 0.617021 (-4488 2862);
PAINT ORANGE (-4488 2862);
FORCEPROP 1 LAST VALUE 0.0
J 0
(-4750 2725);
DISPLAY 0.617021 (-4750 2725);
PAINT SKYBLUE (-4750 2725);
FORCEPROP 1 LAST PART_NUMBER G21497-005
J 0
(-4450 2725);
DISPLAY 0.617021 (-4450 2725);
PAINT BLUE (-4450 2725);
FORCEPROP 1 LAST PACK_TYPE 0402
J 0
(-4450 2775);
DISPLAY 0.617021 (-4450 2775);
PAINT SKYBLUE (-4450 2775);
FORCEPROP 1 LAST MATERIAL CHIP
J 0
(-4300 2775);
DISPLAY 0.617021 (-4300 2775);
PAINT SKYBLUE (-4300 2775);
FORCEPROP 2 LAST CDS_LIB mstr_discrete
J 0
(-4550 2850);
PAINT ORANGE (-4550 2850);
DISPLAY INVISIBLE (-4550 2850);
FORCEPROP 2 LAST SEC 1
J 0
(-4600 3050);
DISPLAY 0.680851 (-4600 3050);
PAINT MONO (-4600 3050);
DISPLAY INVISIBLE (-4600 3050);
FORCEPROP 2 LAST SEC_TYPE 0402
J 0
(-4600 3050);
DISPLAY 1.021277 (-4600 3050);
PAINT ORANGE (-4600 3050);
DISPLAY INVISIBLE (-4600 3050);
FORCEPROP 0 LAST ROOM PCIE_WAKE_BUFFER
J 0
(-4600 3000);
DISPLAY 1.021277 (-4600 3000);
PAINT ORANGE (-4600 3000);
DISPLAY INVISIBLE (-4600 3000);
FORCEPROP 1 LAST PATH I33
J 0
(-4600 3000);
DISPLAY 0.978723 (-4600 3000);
PAINT WHITE (-4600 3000);
DISPLAY INVISIBLE (-4600 3000);
FORCEPROP 2 LAST CDS_LOCATION R8E21
J 0
(-4600 2900);
DISPLAY 0.617021 (-4600 2900);
PAINT AQUA (-4600 2900);
DISPLAY INVISIBLE (-4600 2900);
FORCEADD 2K15R2F-1-GP..1
(-4800 3525);
FORCEPROP 2 LAST ATTRIBUTE 2.15K OHM
J 0
(-4750 3550);
DISPLAY 0.638298 (-4750 3550);
PAINT GREEN (-4750 3550);
FORCEPROP 2 LASTPIN (-4800 3400) $PN 2
R 1
J 2
(-4810 3390);
DISPLAY 0.808511 (-4810 3390);
PAINT ORANGE (-4810 3390);
FORCEPROP 2 LASTPIN (-4800 3650) $PN 1
R 1
J 0
(-4810 3660);
DISPLAY 0.808511 (-4810 3660);
PAINT ORANGE (-4810 3660);
FORCEPROP 2 LAST TOLERANCE 1%
J 0
(-4750 3500);
DISPLAY 0.638298 (-4750 3500);
PAINT GREEN (-4750 3500);
FORCEPROP 2 LAST PACK_SIZE 0402
J 0
(-4750 3400);
DISPLAY 0.638298 (-4750 3400);
PAINT GREEN (-4750 3400);
FORCEPROP 2 LAST RATED 1/16W
J 0
(-4750 3450);
DISPLAY 0.638298 (-4750 3450);
PAINT GREEN (-4750 3450);
FORCEPROP 1 LAST LOCATION R8E36
J 0
(-4750 3655);
DISPLAY 0.617021 (-4750 3655);
PAINT GREEN (-4750 3655);
FORCEPROP 1 LAST VALUE 2K15R2F-1-GP
J 0
(-4750 3600);
DISPLAY 0.617021 (-4750 3600);
PAINT GREEN (-4750 3600);
FORCEPROP 1 LAST CDS_LMAN_SYM_OUTLINE -50,75,50,-75
J 0
(-4800 3525);
DISPLAY 0.468085 (-4800 3525);
PAINT GREEN (-4800 3525);
DISPLAY INVISIBLE (-4800 3525);
FORCEPROP 1 LAST PATH I34
J 0
(-4800 3525);
DISPLAY 0.617021 (-4800 3525);
PAINT GREEN (-4800 3525);
DISPLAY INVISIBLE (-4800 3525);
FORCEPROP 2 LAST CDS_LIB w_hdl
J 0
(-4800 3525);
DISPLAY INVISIBLE (-4800 3525);
FORCEPROP 1 LAST PART_NUMBER 64.21515.6DL
J 0
(-4800 3525);
DISPLAY 0.617021 (-4800 3525);
PAINT GREEN (-4800 3525);
DISPLAY INVISIBLE (-4800 3525);
FORCEPROP 1 LAST PACK_TYPE SMD-RG1
J 0
(-4800 3525);
DISPLAY 0.617021 (-4800 3525);
PAINT GREEN (-4800 3525);
DISPLAY INVISIBLE (-4800 3525);
FORCEPROP 2 LAST SEC 1
J 0
(-4450 3650);
DISPLAY 0.680851 (-4450 3650);
PAINT MONO (-4450 3650);
DISPLAY INVISIBLE (-4450 3650);
FORCEPROP 2 LAST SEC_TYPE SMD-RG1
J 0
(-4450 3650);
DISPLAY 1.021277 (-4450 3650);
PAINT ORANGE (-4450 3650);
DISPLAY INVISIBLE (-4450 3650);
FORCEADD 2K15R2F-1-GP..1
(-3800 3525);
FORCEPROP 2 LASTPIN (-3800 3400) $PN 2
R 1
J 2
(-3810 3390);
DISPLAY 0.808511 (-3810 3390);
PAINT ORANGE (-3810 3390);
FORCEPROP 1 LAST LOCATION R8E30
J 0
(-3750 3655);
DISPLAY 0.617021 (-3750 3655);
PAINT GREEN (-3750 3655);
FORCEPROP 2 LAST TOLERANCE 1%
J 0
(-3750 3500);
DISPLAY 0.638298 (-3750 3500);
PAINT GREEN (-3750 3500);
FORCEPROP 2 LAST PACK_SIZE 0402
J 0
(-3750 3400);
DISPLAY 0.638298 (-3750 3400);
PAINT GREEN (-3750 3400);
FORCEPROP 1 LAST VALUE 2K15R2F-1-GP
J 0
(-3750 3600);
DISPLAY 0.617021 (-3750 3600);
PAINT GREEN (-3750 3600);
FORCEPROP 2 LAST ATTRIBUTE 2.15K OHM
J 0
(-3750 3550);
DISPLAY 0.638298 (-3750 3550);
PAINT GREEN (-3750 3550);
FORCEPROP 2 LAST RATED 1/16W
J 0
(-3750 3450);
DISPLAY 0.638298 (-3750 3450);
PAINT GREEN (-3750 3450);
FORCEPROP 2 LASTPIN (-3800 3650) $PN 1
R 1
J 0
(-3810 3660);
DISPLAY 0.808511 (-3810 3660);
PAINT ORANGE (-3810 3660);
FORCEPROP 1 LAST CDS_LMAN_SYM_OUTLINE -50,75,50,-75
J 0
(-3800 3525);
DISPLAY 0.468085 (-3800 3525);
PAINT GREEN (-3800 3525);
DISPLAY INVISIBLE (-3800 3525);
FORCEPROP 2 LAST CDS_LIB w_hdl
J 0
(-3800 3525);
DISPLAY INVISIBLE (-3800 3525);
FORCEPROP 1 LAST PART_NUMBER 64.21515.6DL
J 0
(-3800 3525);
DISPLAY 0.617021 (-3800 3525);
PAINT GREEN (-3800 3525);
DISPLAY INVISIBLE (-3800 3525);
FORCEPROP 1 LAST PATH I35
J 0
(-3800 3525);
DISPLAY 0.617021 (-3800 3525);
PAINT GREEN (-3800 3525);
DISPLAY INVISIBLE (-3800 3525);
FORCEPROP 2 LAST SEC_TYPE SMD-RG1
J 0
(-3750 3700);
DISPLAY 1.021277 (-3750 3700);
PAINT ORANGE (-3750 3700);
DISPLAY INVISIBLE (-3750 3700);
FORCEPROP 2 LAST SEC 1
J 0
(-3750 3700);
DISPLAY 0.680851 (-3750 3700);
PAINT MONO (-3750 3700);
DISPLAY INVISIBLE (-3750 3700);
FORCEPROP 1 LAST PACK_TYPE SMD-RG1
J 0
(-3800 3525);
DISPLAY 0.617021 (-3800 3525);
PAINT GREEN (-3800 3525);
DISPLAY INVISIBLE (-3800 3525);
FORCEADD P3V3_STBY..1
(-2525 2950);
FORCEPROP 3 LASTPIN (-2525 2900) SIG_NAME P3V3_STBY\g
J 0
(-2515 2910);
DISPLAY 0.659574 (-2515 2910);
PAINT MONO (-2515 2910);
DISPLAY INVISIBLE (-2515 2910);
FORCEPROP 1 LAST HDL_POWER P3V3_STBY
J 0
(-2825 2825);
DISPLAY 0.872340 (-2825 2825);
PAINT ORANGE (-2825 2825);
DISPLAY INVISIBLE (-2825 2825);
FORCEPROP 1 LAST BODY_TYPE PLUMBING
J 0
(-2570 2907);
DISPLAY 0.340426 (-2570 2907);
PAINT GREEN (-2570 2907);
DISPLAY INVISIBLE (-2570 2907);
FORCEPROP 1 LAST PATH I4
J 0
(-2480 2952);
DISPLAY 0.340426 (-2480 2952);
PAINT GREEN (-2480 2952);
DISPLAY INVISIBLE (-2480 2952);
FORCEPROP 1 LAST SIZE 1B
J 0
(-2480 2972);
DISPLAY 0.340426 (-2480 2972);
PAINT GREEN (-2480 2972);
DISPLAY INVISIBLE (-2480 2972);
FORCEPROP 2 LAST CDS_LIB mstr_symbols
J 0
(-2525 2950);
PAINT ORANGE (-2525 2950);
DISPLAY INVISIBLE (-2525 2950);
FORCEPROP 1 LAST VOLTAGE 3.3V
J 0
(-2570 2907);
DISPLAY 0.340426 (-2570 2907);
PAINT SKYBLUE (-2570 2907);
DISPLAY INVISIBLE (-2570 2907);
FORCEADD OFFPAGE..2
(-1650 2250);
FORCEPROP 2 LAST $XR0 118 
J 0
(-1461 2250);
DISPLAY 0.638298 (-1461 2250);
PAINT MONO (-1461 2250);
FORCEPROP 1 LAST COMMENT_BODY TRUE
J 0
(-1695 2155);
DISPLAY 0.872340 (-1695 2155);
PAINT GREEN (-1695 2155);
DISPLAY INVISIBLE (-1695 2155);
FORCEPROP 1 LAST OFFPAGE TRUE
J 0
(-1325 2125);
DISPLAY 0.872340 (-1325 2125);
PAINT GREEN (-1325 2125);
DISPLAY INVISIBLE (-1325 2125);
FORCEPROP 2 LAST PATH I5
J 0
(-1600 2325);
DISPLAY 1.021277 (-1600 2325);
PAINT ORANGE (-1600 2325);
DISPLAY INVISIBLE (-1600 2325);
FORCEPROP 2 LAST CDS_LIB mstr_standard
J 0
(-1650 2250);
PAINT ORANGE (-1650 2250);
DISPLAY INVISIBLE (-1650 2250);
FORCEADD CAD_NOTE..1
(-4750 4250);
FORCEPROP 0 LAST L1 ADD PULLUP NEAR X24 CONN
J 0
(-4900 4125);
DISPLAY 1.021277 (-4900 4125);
PAINT ORANGE (-4900 4125);
FORCEPROP 1 LAST COMMENT_BODY TRUE
J 0
(-4725 4350);
DISPLAY 0.978723 (-4725 4350);
PAINT ORANGE (-4725 4350);
DISPLAY INVISIBLE (-4725 4350);
FORCEPROP 2 LAST CDS_LIB mstr_symbols
J 0
(-4750 4250);
PAINT ORANGE (-4750 4250);
DISPLAY INVISIBLE (-4750 4250);
FORCEADD DESIGN_NOTE..1
(-2925 1600);
FORCEPROP 0 LAST L1 PLACE CAP CLOSE TO TRI STATE BUFFER
J 0
(-3100 1450);
DISPLAY 1.021277 (-3100 1450);
PAINT ORANGE (-3100 1450);
FORCEPROP 1 LAST COMMENT_BODY TRUE
J 0
(-2900 1700);
DISPLAY 0.978723 (-2900 1700);
PAINT ORANGE (-2900 1700);
DISPLAY INVISIBLE (-2900 1700);
FORCEPROP 2 LAST CDS_LIB mstr_symbols
J 0
(-2925 1600);
PAINT ORANGE (-2925 1600);
DISPLAY INVISIBLE (-2925 1600);
FORCEADD DNS..2
(-4545 3120);
PAINT RED (-4545 3120);
FORCEPROP 1 LAST COMMENT_BODY TRUE
R 1
J 0
(-4470 2895);
DISPLAY 0.872340 (-4470 2895);
PAINT GREEN (-4470 2895);
DISPLAY INVISIBLE (-4470 2895);
FORCEPROP 2 LAST CDS_LIB mstr_misc
J 0
(-4545 3120);
PAINT ORANGE (-4545 3120);
DISPLAY INVISIBLE (-4545 3120);
FORCEADD INTEL_CORP_BPAGE..1
(0 0);
FORCEPROP 1 LAST CDS_CON_LAST_MODIFIED Fri Jun 16 17:48:53 2017
J 0
(-1425 325);
DISPLAY 0.659574 (-1425 325);
PAINT GREEN (-1425 325);
DISPLAY INVISIBLE (-1425 325);
FORCEPROP 1 LAST CUSTOM_TXT_CDS <CURRENT_DESIGN_SHEET> OF <TOTAL_DESIGN_SHEETS>
J 0
(-500 25);
PAINT ORANGE (-500 25);
FORCEPROP 1 LAST CUSTOM_TXT_CDS <CON_LAST_MODIFIED>
J 0
(-4000 100);
PAINT ORANGE (-4000 100);
FORCEPROP 2 LAST CUSTOM_TXT_CDS <XR_PAGE_TITLE>
J 0
(-7890 5250);
DISPLAY 0.638298 (-7890 5250);
PAINT PINK (-7890 5250);
DISPLAY INVISIBLE (-7890 5250);
FORCEPROP 1 LAST SCH_TITLE PCIE WAKE TRI-STATE BUFFER
J 0
(-7950 50);
DISPLAY 1.212766 (-7950 50);
PAINT GREEN (-7950 50);
FORCEPROP 1 LAST COMMENT_BODY TRUE
J 0
(12 12);
DISPLAY 0.319149 (12 12);
PAINT GREEN (12 12);
DISPLAY INVISIBLE (12 12);
FORCEPROP 2 LAST CDS_LIB mstr_symbols
J 0
(0 0);
DISPLAY 0.489362 (0 0);
PAINT ORANGE (0 0);
DISPLAY INVISIBLE (0 0);
FORCEPROP 2 LAST PAGE_BORDER TRUE
J 0
(-7890 5250);
DISPLAY 0.425532 (-7890 5250);
PAINT PINK (-7890 5250);
DISPLAY INVISIBLE (-7890 5250);
FORCEPROP 2 LAST CDS_XR_PAGE_TITLE CR-142 : @BASEBOARD_FAB2_LIB.BASEBOARD_FAB2(SCH_1):PAGE142
J 0
(-7890 5250);
DISPLAY 0.638298 (-7890 5250);
PAINT PINK (-7890 5250);
DISPLAY INVISIBLE (-7890 5250);
WIRE 16 -1 (-3500 1650)(-3500 1725);
WIRE 16 -1 (-3500 1300)(-3500 1450);
WIRE 16 -1 (-3800 3850)(-3800 3750);
WIRE 16 -1 (-4800 3750)(-3800 3750);
WIRE 16 -1 (-3800 3750)(-3800 3650);
WIRE 16 -1 (-4800 3650)(-4800 3750);
WIRE 16 -1 (-2525 2700)(-2525 2900);
WIRE 16 -1 (-2750 2700)(-2525 2700);
WIRE 16 2175 (-3850 4350)(-4950 4350);
WIRE 16 2175 (-4950 4350)(-4950 3250);
WIRE 16 2175 (-3850 4050)(-3850 4350);
WIRE 16 2175 (-4050 4050)(-3850 4050);
WIRE 16 2175 (-4950 3250)(-4050 3250);
WIRE 16 2175 (-4050 3250)(-4050 4050);
WIRE 3 682 (-4900 3800)(-4900 3300);
WIRE 3 682 (-3450 3800)(-4900 3800);
WIRE 3 682 (-4900 3300)(-3450 3300);
WIRE 3 682 (-3450 3300)(-3450 3800);
WIRE 16 -1 (-4450 2250)(-3800 2250);
WIRE 16 -1 (-3800 2250)(-3650 2250);
WIRE 16 -1 (-3800 2450)(-4450 2450);
WIRE 16 -1 (-3800 2450)(-3800 2250);
WIRE 16 -1 (-4450 2650)(-3800 2650);
WIRE 16 -1 (-3800 2650)(-3800 2450);
WIRE 16 -1 (-4450 2850)(-3800 2850);
WIRE 16 -1 (-3800 2850)(-3800 2650);
WIRE 16 -1 (-3800 3100)(-3800 2850);
WIRE 16 -1 (-3800 3400)(-3800 3100);
WIRE 16 -1 (-4450 3100)(-3800 3100);
FORCEPROP 2 LAST SIG_NAME FM_ALL_WAKE_N
J 0
(-4335 3110);
DISPLAY 0.617021 (-4335 3110);
PAINT ORANGE (-4335 3110);
FORCEPROP 2 LASTPROP $XRERR UNIQUE?
J 0
(-4575 3110);
DISPLAY 0.638298 (-4575 3110);
PAINT MONO (-4575 3110);
DISPLAY INVISIBLE (-4575 3110);
WIRE 16 -1 (-4650 2450)(-4800 2450);
WIRE 16 -1 (-4800 3400)(-4800 2450);
WIRE 16 -1 (-5400 2450)(-4800 2450);
FORCEPROP 2 LAST SIG_NAME FM_PE_SLOTX24_WAKE_N
J 0
(-5350 2460);
DISPLAY 0.617021 (-5350 2460);
PAINT ORANGE (-5350 2460);
WIRE 16 -1 (-5400 3100)(-4650 3100);
FORCEPROP 2 LAST SIG_NAME FM_PE_BMC_WAKE_N
J 0
(-5350 3110);
DISPLAY 0.617021 (-5350 3110);
PAINT ORANGE (-5350 3110);
WIRE 16 -1 (-4650 2250)(-5400 2250);
FORCEPROP 2 LAST SIG_NAME FM_PE_OCP_WAKE_N
J 0
(-5350 2260);
DISPLAY 0.617021 (-5350 2260);
PAINT ORANGE (-5350 2260);
WIRE 16 -1 (-4650 2650)(-5400 2650);
FORCEPROP 2 LAST SIG_NAME FM_PE_M2_WAKE_N
J 0
(-5350 2660);
DISPLAY 0.617021 (-5350 2660);
PAINT ORANGE (-5350 2660);
WIRE 16 -1 (-5400 2850)(-4650 2850);
FORCEPROP 2 LAST SIG_NAME FM_PE_SPRV_WAKE_N
J 0
(-5350 2860);
DISPLAY 0.617021 (-5350 2860);
PAINT ORANGE (-5350 2860);
WIRE 16 -1 (-2500 2250)(-1700 2250);
FORCEPROP 2 LAST SIG_NAME IRQ_LVC3_WAKE_N
J 0
(-2160 2260);
DISPLAY 0.617021 (-2160 2260);
PAINT ORANGE (-2160 2260);
WIRE 16 -1 (-3350 2250)(-2700 2250);
FORCEPROP 2 LAST SIG_NAME IRQ_LVC3_WAKE_R_N
J 0
(-3285 2260);
DISPLAY 0.617021 (-3285 2260);
PAINT ORANGE (-3285 2260);
FORCEPROP 2 LASTPROP $XRERR UNIQUE?
J 0
(-3525 2260);
DISPLAY 0.638298 (-3525 2260);
PAINT MONO (-3525 2260);
DISPLAY INVISIBLE (-3525 2260);
WIRE 16 -1 (-3500 2350)(-3500 2700);
WIRE 16 -1 (-3500 2700)(-2950 2700);
FORCEPROP 2 LAST SIG_NAME PU_TRI_STATE_EN
J 0
(-3410 2710);
DISPLAY 0.617021 (-3410 2710);
PAINT ORANGE (-3410 2710);
FORCEPROP 2 LASTPROP $XRERR UNIQUE?
J 0
(-3650 2710);
DISPLAY 0.638298 (-3650 2710);
PAINT MONO (-3650 2710);
DISPLAY INVISIBLE (-3650 2710);
DOT 1 (-3800 3750);
DOT 1 (-3800 2250);
DOT 1 (-3800 2450);
DOT 1 (-4800 2450);
DOT 1 (-3800 2650);
DOT 1 (-3800 2850);
DOT 1 (-3800 3100);
FORCENOTE
TP FAB3 CHANGE RES 0803
(-4900 3825) 0;
DISPLAY LEFT (-4900 3825);
DISPLAY 0.808511 (-4900 3825);
PAINT RED (-4900 3825);
QUIT
